# BASEBOARD_FAB2 (Tioga Pass) — schematic netlist excerpt (pin names and nets, part order shuffled) for the footprints in the layout excerpt that follows; sources: Cadence DE-HDL packaged netlist, KiCad conversion of Wiwynn_Tioga_Pass_MB.brd

C7E12  SC22U16V5MX-4-GP  20%  pkg SMD-BCG5  page 241 : \1\ = VR_FET_SW_P5V_STBY_PVIN ; \2\ = GND

U25W19  TTL1G126_A  74HC1G126 IC  pkg SOT  page 254
  OE  = BMC_JTAG_SEL_BUF
  A  = JTAG_BMC_TCK
  Y  = JTAG_BMC_TCK_BUF

R1D8  RES  1.00K 1% CHIP  pkg 0402  page 206 : A = P3V3_STBY ; B = PWRGD_PVSA_CPU1_R

(kicad_pcb
	(version 20260206)
	(generator "pcbnew")
	(generator_version "10.0")
	(general
		(thickness 1.6)
		(legacy_teardrops no)
	)
	(paper "A4")
	(title_block
		(title "Wiwynn_Tioga_Pass_MB.brd")
		(comment 1 "Tioga Pass / footprints 1154-1156 of 4770")
	)
	(layers
		(0 "F.Cu" signal "TOP")
		(4 "In1.Cu" signal "L2GND")
		(6 "In2.Cu" signal "L3")
		(8 "In3.Cu" signal "L4GND")
		(10 "In4.Cu" signal "L5")
		(12 "In5.Cu" signal "L6GND")
		(14 "In6.Cu" signal "L7VCC")
		(16 "In7.Cu" signal "L8VCC")
		(18 "In8.Cu" signal "L9GND")
		(20 "In9.Cu" signal "L10")
		(22 "In10.Cu" signal "L11GND")
		(24 "In11.Cu" signal "L12")
		(26 "In12.Cu" signal "L13GND")
		(2 "B.Cu" signal "BOTTOM")
		(9 "F.Adhes" user "F.Adhesive")
		(11 "B.Adhes" user "B.Adhesive")
		(13 "F.Paste" user "Package Geometry/Pastemask Top")
		(15 "B.Paste" user "Package Geometry/Pastemask Bottom")
		(5 "F.SilkS" user "Ref Des/Silkscreen Top")
		(7 "B.SilkS" user "Ref Des/Silkscreen Bottom")
		(1 "F.Mask" user "Board Geometry/Soldermask Top")
		(3 "B.Mask" user "Board Geometry/Soldermask Bottom")
		(17 "Dwgs.User" user "User.Drawings")
		(19 "Cmts.User" user "User.Comments")
		(21 "Eco1.User" user "User.Eco1")
		(23 "Eco2.User" user "User.Eco2")
		(25 "Edge.Cuts" user "Board Geometry/Outline")
		(27 "Margin" user)
		(31 "F.CrtYd" user "Package Geometry/Place Bound Top")
		(29 "B.CrtYd" user "Package Geometry/Place Bound Bottom")
		(35 "F.Fab" user "Ref Des/Assembly Top")
		(33 "B.Fab" user "Ref Des/Assembly Bottom")
	)
	(footprint ""
		(layer "F.Cu")
		(at 385.8768 -65.3034)
		(property "Reference" "C7E12"
			(at 0 0 0)
			(layer "F.SilkS")
			(hide yes)
			(effects
				(font
					(size 1.27 1.27)
				)
			)
		)
		(property "Value" "*"
			(at -0.0762 -6.2357 0)
			(unlocked yes)
			(layer "F.Fab")
			(hide yes)
			(effects
				(font
					(size 1.27 1.016)
					(thickness 0.1524)
				)
			)
		)
		(property "Device Type" "SC22U16V5MX-4-GP_SMD-BCG5-SC22A"
			(at -0.0762 -8.2677 0)
			(unlocked yes)
			(layer "F.Fab")
			(hide yes)
			(effects
				(font
					(size 1.27 1.016)
					(thickness 0.1524)
				)
			)
		)
		(duplicate_pad_numbers_are_jumpers no)
		(fp_line
			(start 0.635 0)
			(end -0.635 0)
			(stroke
				(width 0.508)
				(type default)
			)
			(layer "F.SilkS")
		)
		(fp_rect
			(start -0.9652 1.778)
			(end 0.9652 -1.778)
			(stroke
				(width 0)
				(type default)
			)
			(fill no)
			(layer "F.CrtYd")
		)
		(fp_poly
			(pts
				(xy -0.9652 -1.778) (xy 0.9652 -1.778) (xy 0.9652 1.778) (xy -0.9652 1.778)
			)
			(stroke
				(width 0)
				(type default)
			)
			(fill no)
			(layer "F.Fab")
		)
		(pad "1" smd rect
			(at 0 -0.9652)
			(size 1.397 1.143)
			(layers "F.Cu" "F.Mask" "F.Paste")
			(net "VR_FET_SW_P5V_STBY_PVIN")
		)
		(pad "2" smd rect
			(at 0 0.9652)
			(size 1.397 1.143)
			(layers "F.Cu" "F.Mask" "F.Paste")
			(net "GND")
		)
	)
	(footprint ""
		(layer "F.Cu")
		(at 439.626756 -146.477228)
		(property "Reference" "U25W19"
			(at -0.14986 2.621788 0)
			(unlocked yes)
			(layer "F.SilkS")
			(effects
				(font
					(size 1.27 0.964946)
					(thickness 0.000001)
				)
				(justify left)
			)
		)
		(property "Value" ""
			(at 0 0 0)
			(layer "F.Fab")
			(effects
				(font
					(size 1.27 1.27)
				)
			)
		)
		(duplicate_pad_numbers_are_jumpers no)
		(fp_circle
			(center -0.4699 -0.8382)
			(end -0.3429 -0.8382)
			(stroke
				(width 0.254)
				(type default)
			)
			(fill no)
			(layer "F.SilkS")
		)
		(fp_poly
			(pts
				(xy 0.21463 -0.450088) (xy 1.56337 -0.450088) (xy 1.56337 1.75006) (xy 0.21463 1.75006)
			)
			(stroke
				(width 0)
				(type default)
			)
			(fill no)
			(layer "F.CrtYd")
		)
		(fp_line
			(start 0.21463 -0.450088)
			(end 1.56337 -0.450088)
			(stroke
				(width 0.1)
				(type default)
			)
			(layer "F.Fab")
		)
		(fp_line
			(start 0.21463 1.75006)
			(end 0.21463 -0.450088)
			(stroke
				(width 0.1)
				(type default)
			)
			(layer "F.Fab")
		)
		(fp_line
			(start 1.56337 -0.450088)
			(end 1.56337 1.75006)
			(stroke
				(width 0.1)
				(type default)
			)
			(layer "F.Fab")
		)
		(fp_line
			(start 1.56337 1.75006)
			(end 0.21463 1.75006)
			(stroke
				(width 0.1)
				(type default)
			)
			(layer "F.Fab")
		)
		(fp_circle
			(center -0.4699 -0.8382)
			(end -0.3429 -0.8382)
			(stroke
				(width 0.254)
				(type default)
			)
			(fill no)
			(layer "F.Fab")
		)
		(pad "1" smd rect
			(at 0 0)
			(size 1.016 0.381)
			(layers "F.Cu" "F.Mask" "F.Paste")
			(net "BMC_JTAG_SEL_BUF")
		)
		(pad "2" smd rect
			(at 0 0.649986)
			(size 1.016 0.381)
			(layers "F.Cu" "F.Mask" "F.Paste")
			(net "JTAG_BMC_TCK")
		)
		(pad "3" smd rect
			(at 0 1.299972)
			(size 1.016 0.381)
			(layers "F.Cu" "F.Mask" "F.Paste")
			(net "GND")
		)
		(pad "4" smd rect
			(at 1.778 1.299972)
			(size 1.016 0.381)
			(layers "F.Cu" "F.Mask" "F.Paste")
			(net "JTAG_BMC_TCK_BUF")
		)
		(pad "5" smd rect
			(at 1.778 0)
			(size 1.016 0.381)
			(layers "F.Cu" "F.Mask" "F.Paste")
			(net "P3V3_STBY")
		)
	)
	(footprint ""
		(layer "F.Cu")
		(at 16.764 -86.741 180)
		(property "Reference" "R1D8"
			(at 0 0 180)
			(layer "F.SilkS")
			(hide yes)
			(effects
				(font
					(size 1.27 1.27)
				)
			)
		)
		(property "Value" ""
			(at 0 0 180)
			(layer "F.Fab")
			(effects
				(font
					(size 1.27 1.27)
				)
			)
		)
		(duplicate_pad_numbers_are_jumpers no)
		(fp_rect
			(start 0.2794 -0.1016)
			(end -0.2794 0.9906)
			(stroke
				(width 0)
				(type default)
			)
			(fill no)
			(layer "F.CrtYd")
		)
		(fp_line
			(start 0.2794 0.9906)
			(end 0.2794 -0.1016)
			(stroke
				(width 0.1)
				(type default)
			)
			(layer "F.Fab")
		)
		(fp_line
			(start 0.2794 -0.1016)
			(end -0.2794 -0.1016)
			(stroke
				(width 0.1)
				(type default)
			)
			(layer "F.Fab")
		)
		(fp_line
			(start -0.2794 0.9906)
			(end 0.2794 0.9906)
			(stroke
				(width 0.1)
				(type default)
			)
			(layer "F.Fab")
		)
		(fp_line
			(start -0.2794 -0.1016)
			(end -0.2794 0.9906)
			(stroke
				(width 0.1)
				(type default)
			)
			(layer "F.Fab")
		)
		(pad "1" smd rect
			(at 0 0 180)
			(size 0.508 0.508)
			(layers "F.Cu" "F.Mask" "F.Paste")
			(net "P3V3_STBY")
		)
		(pad "2" smd rect
			(at 0 0.889 180)
			(size 0.508 0.508)
			(layers "F.Cu" "F.Mask" "F.Paste")
			(net "PWRGD_PVSA_CPU1_R")
		)
		(zone
			(layer "F.Cu")
			(hatch none 0.5)
			(connect_pads
				(clearance 0)
			)
			(min_thickness 0.25)
			(keepout
				(tracks allowed)
				(vias not_allowed)
				(pads allowed)
				(copperpour not_allowed)
				(footprints allowed)
			)
			(placement
				(enabled no)
				(sheetname "")
			)
			(fill
				(thermal_gap 0.5)
				(thermal_bridge_width 0.5)
				(island_removal_mode 0)
			)
			(polygon
				(pts
					(xy 16.51 -86.995) (xy 17.018 -86.995) (xy 17.018 -87.376) (xy 16.51 -87.376)
				)
			)
		)
		(zone
			(layer "F.Cu")
			(hatch none 0.5)
			(connect_pads
				(clearance 0)
			)
			(min_thickness 0.25)
			(keepout
				(tracks not_allowed)
				(vias allowed)
				(pads allowed)
				(copperpour not_allowed)
				(footprints allowed)
			)
			(placement
				(enabled no)
				(sheetname "")
			)
			(fill
				(thermal_gap 0.5)
				(thermal_bridge_width 0.5)
				(island_removal_mode 0)
			)
			(polygon
				(pts
					(xy 16.51 -86.995) (xy 17.018 -86.995) (xy 17.018 -87.376) (xy 16.51 -87.376)
				)
			)
		)
	)
)
